# SCM (Grand Teton) — schematic netlist excerpt (pin names and nets, part order shuffled) for the footprints in the layout excerpt that follows; sources: Cadence DE-HDL packaged netlist, KiCad conversion of 12092022_DA0F0TMDCD0_F0T_Management_Board_D_brd_V3_OCP.brd

U25  LCMXO3LF2100C5BG256C  LCMXO3LF-2100C-5BG256C IC  pkg BGA256_0-8_14X14  page 34
  VCC_A1  = PVCCA_AUX_PLD
  NC1  = NC
  PT11C  = BSM_PRSNT_R1_N
  PT10A  = RST_PLTRST_R1_N
  PT11A  = RST_RSMRST_N
  \pt12d||tdi\  = JTAG_SCM_PLD_TDI
  \pt16c||tck\  = JTAG_SCM_PLD_TCK
  \pt17b||pclkc0_1\  = IRQ_BMC_PCH_NMI_R_N
  \pt18c||scl||pclkt0_0\  = SMB_BMC_MM16_R3_SCL
  PT19B  = NC
  PT21A  = RST_EXTRST_R_N
  PT22B  = FM_ADR_COMPLETE
  \pt24c||initn\  = PU_FPGA_NSTATUS
  PT22D  = SGPIO_CLK_PLD_0
  PT24B  = FM_THERMTRIP_DLY_LVC1_R_N
  VCC_A16  = PVCCA_AUX_PLD
  PL1C  = NC
  GND_B2  = GND
  PT9C  = IRQ_BMC_CPU_NMI_R
  PT11D  = RST_PCA9548_SENSOR_N
  PT9B  = FM_TPM_PRSNT_1_R_N
  PT11B  = FM_JTAG_BMC_MUX_SEL_R2
  PT13A  = IRQ_UV_DETECT_N
  \pt16d||tms\  = JTAG_SCM_PLD_TMS
  PT19A  = IRQ_PCH_SCI_WHEA_N
  \pt20d||programn\  = PU_PT20D
  PT22A  = IRQ_OC_DETECT_N
  PT23B  = SGPIO_PLD_LD_0
  PT22C  = IRQ_OC_DETECT_EN_N
  PT24A  = SGPIO_PLD_DI_0
  GND_B15  = GND
  PR1D  = FM_PECI_SEL_N
  PL2C  = NC
  PL1D  = NC
  GND_C3  = GND
  PT9A  = FM_TPM_PRSNT_0_R_N
  PT10B  = PWRGD_PSU_AC_PWROK_PLD
  \pt12c||tdo\  = JTAG_SCM_PLD_TDO
  PT13B  = RST_BMC_RSTBTN_OUT_N
  \pt17a||pclkt0_1\  = CLK_25M_OSC_FPGA
  \pt18d||sda||pclkc0_0\  = SMB_BMC_MM16_R3_SDA
  \pt20c||jtagenb\  = JTAG_SCM_PLD_R_JTAGEN
  PT21B  = PWRGD_CPUPWRGD_LVC1
  PT23A  = SGPIO_PLD_DO_0
  \pt24d||done\  = PU_FPGA_CONFIG_DONE
  GND_C14  = GND
  PR1C  = VOL_SEN_ALERT_R
  PR2C  = SMB_BMC_ALERT3_R1_N
  \pl1b||l_gpllc_fb\  = NC
  PL2D  = NC
  \pl1a||l_gpllt_fb\  = NC
  GND_D4  = GND
  VCCIO0_D5  = VCCIO0
  PT12A  = FM_BMC_DBP_PRESENT_N
  PT13D  = FM_ME_BT_DONE
  PT17C  = FM_PCH_BMC_THERMTRIP_N
  PT18B  = NC
  PT20A  = NC
  PT21D  = IRQ_CPU1_VRHOT_N
  VCCIO0_D12  = VCCIO0
  GND_D13  = GND
  PR1A  = H_CPU0_MEMTRIP_LVC1_N
  PR2D  = SMB_BMC_ALERT4_R1_N
  PR2A  = H_CPU1_MEMTRIP_LVC1_N
  \pl3a||pclkt5_0\  = NC
  \pl2a||l_gpllt_in\  = NC
  \pl2b||l_gpllc_in\  = NC
  VCCIO5  = VCCIO5
  GND_E5  = GND
  PT13C  = BMC_CPLD_GPIO_2_R2
  PT12B  = PWRGD_PCH_PWROK
  PT16B  = FM_BIOS_POST_CMPLT_BMC_N
  PT17D  = H_CPU1_PROCHOT_LVC1_R_N
  PT20B  = FM_CPU_MSMI_CATERR_LVT3_PLD_N
  PT19D  = TP_PLD_19D
  GND_E12  = GND
  VCCIO1_E13  = VCCIO1
  PR2B  = IRQ_SGPIO_R_N
  PR1B  = FM_SPD_REMOTE_EN_R
  PR3A  = RST_SGPIO_RESET_R_N
  PL4B  = NC
  \pl3b||pclkc5_0\  = NC
  PL4A  = NC
  PL3C  = NC
  PL5C  = NC
  GND_F6  = GND
  PT16A  = FM_PCIE_M2_SSD0_PRSNT_N
  PT18A  = RST_SRST_PLD_BMC_R2_N
  PT19C  = NC
  PT21C  = IRQ_CPU0_VRHOT_N
  GND_F11  = GND
  PR4C  = TP_PLD_L3
  PR3C  = SMB_BMC_ALERT9_R1_N
  PR4A  = BMC_CPLD_GPIO_8_R2
  PR3B  = BMC_CPLD_GPIO_7_R2
  PR4B  = NC
  PL6A  = NC
  PL5A  = NC
  PL5B  = NC
  PL4D  = NC
  PL4C  = NC
  PL3D  = NC
  VCC_G7  = PVCCA_AUX_PLD
  VCCIO0_G8  = VCCIO0
  VCCIO0_G9  = VCCIO0
  VCC_G10  = PVCCA_AUX_PLD
  PR5C  = FM_SLPS3_GF_R_N
  PR3D  = SMB_BMC_ALERT10_R1_N
  PR4D  = RST_BMC_SELF_HW_R2
  PR5B  = NC
  PR5A  = NC
  PR6A  = BMC_CPLD_GPIO_12_R2
  PL7B  = NC
  PL6B  = NC
  PL7A  = NC
  PL6C  = NC
  PL9C  = NC
  PL5D  = NC
  VCCIO4_H7  = VCCIO4
  GND_H8  = GND
  GND_H9  = GND
  VCCIO1_H10  = VCCIO1
  PR9C  = RST_MB_STBY_R_N
  PR5D  = RST_ROT_CPU_R_N
  PR6C  = FM_ESPI_PLD_R_EN
  \pr7a||pclkt1_0\  = NC
  PR6B  = BMC_CPLD_GPIO_13_R2
  \pr7b||pclkc1_0\  = NC
  \pl7c||pclkt4_0\  = NC
  PL9A  = NC
  \pl7d||pclkc4_0\  = NC
  PL9D  = NC
  PL10C  = NC
  PL6D  = NC
  VCCIO4_J7  = VCCIO4
  GND_J8  = GND
  GND_J9  = GND
  VCCIO1_J10  = VCCIO1
  PR10C  = NC
  PR6D  = FM_THROTTLE_R_N
  PR9D  = FM_ADR_TRIGGER_N
  PR7D  = H_CPU0_PROCHOT_LVC1_R_N
  PR9A  = RST_BMC_HW_R
  PR7C  = FM_PMBUS_ALERT_EN
  PL9B  = NC
  PL10B  = NC
  PL10A  = NC
  PL11C  = NC
  PL12C  = NC
  PL10D  = NC
  VCC_K7  = PVCCA_AUX_PLD
  VCCIO2_K8  = VCCIO2
  VCCIO2_K9  = VCCIO2
  VCC_K10  = PVCCA_AUX_PLD
  PR12C  = FM_PCHHOT_R_N
  PR11D  = FM_BIOS_DEBUG_EN_N
  PR11C  = FM_BMC_READY_PLD_N
  PR10A  = FM_PWR_R_BTN
  PR10B  = PWRGD_SYS_PWROK_PLD
  PR9B  = NC
  PL11A  = NC
  \pl12a||pclkt3_0\  = NC
  PL11B  = NC
  PL12D  = NC
  PL11D  = NC
  GND_L6  = GND
  PB8D  = NC_FM_PFR_NO_SERVICE_ACT_N
  PB11D  = FM_PFR_DSW_PWROK_N
  PB12D  = FM_BMC_CPU_FBRK_OUT_R_N
  PB18D  = FM_UARTSW_MSB_R_N
  GND_L11  = GND
  PR10D  = FM_BMC_EN_DET_R
  PR12D  = FM_BMC_ONCTL_R_N
  PR11B  = SMB_BMC_ALERT12_N
  PR12A  = NC
  PR11A  = USB_OC0_REAR_R_N
  \pl12b||pclkc3_0\  = NC
  PL14A  = NC
  PL13A  = NC
  VCCIO3  = VCCIO3
  GND_M5  = GND
  PB11C  = BMC_MONITER
  PB9C  = CLK_GEN2_BMC_RC_OE_N
  PB16C  = PWRGD_P1V8_AUX_R1
  PB18C  = FM_UARTSW_LSB_R_N
  PB21C  = PU_FPGA_NCONFIG
  PB19D  = NC
  GND_M12  = GND
  VCCIO1_M13  = VCCIO1
  PR13A  = PWR_LED_CPLD
  PR13B  = PWRGD_P5V_AUX_R1
  PR12B  = NC
  PL13B  = NC
  PL13C  = NC
  PL14B  = NC
  GND_N4  = GND
  VCCIO2_N5  = VCCIO2
  PB8C  = FM_BMC_DEBUG_SW_R2_N
  PB9D  = IRQ_SML0_ALERT_R_N
  PB12C  = CLK_BUF1_GPU_FPGA_OE_R_N
  PB16D  = PWRGD_P3V3_RGM_R1
  PB19C  = NC
  PB21D  = NC
  VCCIO2_N12  = VCCIO2
  GND_N13  = GND
  PR14B  = PWRGD_P2V5_AUX_R1
  PR13C  = AC_PWR_BTN_R2_N
  PR14A  = PWRGD_P3V3_AUX_R1
  PL13D  = NC
  PL14D  = NC
  GND_P3  = GND
  PB3A  = FM_P12V_HSC_ENABLE_R2
  PB5B  = TP_PLD_C13
  \pb8a||mclk||cclk\  = FM_HDD_LED_N
  PB9B  = GPU_WP_HW_CTRL_R_N
  PB12A  = GPU_FPGA_RST_N
  \pb16b||pclkc2_1\  = PWRGD_P1V0_AUX_R1
  PB19A  = NC
  PB21B  = NC
  PB24A  = NC
  \pb25b||si||sispi\  = NC
  GND_P14  = GND
  PR14C  = NC
  PR13D  = NC
  PL14C  = NC
  GND_R2  = GND
  PB3D  = PWRGD_DSW_PWROK_R2
  PB6D  = FM_BMC_SUSACK_R2_N
  \pb5a||csspin\  = FM_DEBUG_PORT_R2_PRSNT_N
  PB6B  = FM_BMC_CRASHLOG_TRIG_R2_N
  PB9A  = GPU_NVS_PWR_BRAKE_R_N
  \pb11b||pclkc2_0\  = NC_FM_PFR_UPDATE_N
  PB18A  = NC
  PB19B  = NC
  PB22A  = NC
  \pb25a||sn\  = PU_PB25A
  PB22C  = NC
  PB25D  = SMB_BMC_MM16_R4_SDA
  GND_R15  = GND
  PR14D  = SMB_BMC_ALERT16_R2_N
  VCC_T1  = PVCCA_AUX_PLD
  PB3C  = FM_SOL_UART_CH_SEL_R2
  PB6C  = RST_WDTRST_PLD_R2_N
  PB3B  = NC
  PB6A  = IRQ_PCH_TPM_SPI_R2_N
  \pb8b||so||spiso\  = FM_PCH_BEEP_LED
  \pb11a||pclkt2_0\  = RST_PFR_OVR_RTC_R
  PB12B  = FM_JTAG_TCK_MUX_BMC_SEL
  \pb16a||pclkt2_1\  = PWRGD_P1V2_AUX_R1
  PB18B  = NC
  PB21A  = NC
  PB22B  = NC
  PB24B  = NC
  PB22D  = NC
  PB25C  = SMB_BMC_MM16_R4_SCL
  VCC_T16  = PVCCA_AUX_PLD

(kicad_pcb
	(version 20260206)
	(generator "pcbnew")
	(generator_version "10.0")
	(general
		(thickness 1.6)
		(legacy_teardrops no)
	)
	(paper "A4")
	(title_block
		(title "12092022_DA0F0TMDCD0_F0T_Management_Board_D_brd_V3_OCP.brd")
		(comment 1 "Grand Teton / footprint 162 of 1440 (U25), pads 1-45 of 256")
	)
	(layers
		(0 "F.Cu" signal "TOP")
		(4 "In1.Cu" signal "GND")
		(6 "In2.Cu" signal "IN1")
		(8 "In3.Cu" signal "GND1")
		(10 "In4.Cu" signal "IN2")
		(12 "In5.Cu" signal "VCC")
		(14 "In6.Cu" signal "VCC1")
		(16 "In7.Cu" signal "IN3")
		(18 "In8.Cu" signal "GND2")
		(20 "In9.Cu" signal "IN4")
		(22 "In10.Cu" signal "GND3")
		(2 "B.Cu" signal "BOTTOM")
		(9 "F.Adhes" user "F.Adhesive")
		(11 "B.Adhes" user "B.Adhesive")
		(13 "F.Paste" user "Package Geometry/Pastemask Top")
		(15 "B.Paste" user "Package Geometry/Pastemask Bottom")
		(5 "F.SilkS" user "Ref Des/Silkscreen Top")
		(7 "B.SilkS" user "Ref Des/Silkscreen Bottom")
		(1 "F.Mask" user "Board Geometry/Soldermask Top")
		(3 "B.Mask" user "Board Geometry/Soldermask Bottom")
		(17 "Dwgs.User" user "User.Drawings")
		(19 "Cmts.User" user "User.Comments")
		(21 "Eco1.User" user "User.Eco1")
		(23 "Eco2.User" user "User.Eco2")
		(25 "Edge.Cuts" user "Board Geometry/Outline")
		(27 "Margin" user)
		(31 "F.CrtYd" user "Package Geometry/Place Bound Top")
		(29 "B.CrtYd" user "Package Geometry/Place Bound Bottom")
		(35 "F.Fab" user "Ref Des/Assembly Top")
		(33 "B.Fab" user "Ref Des/Assembly Bottom")
	)
	(footprint ""
		(layer "F.Cu")
		(at 21.459444 -93.587062 180)
		(property "Reference" "U25"
			(at -10.595356 -8.218932 0)
			(unlocked yes)
			(layer "F.SilkS")
			(effects
				(font
					(size 0.7874 0.5842)
					(thickness 0.1524)
				)
				(justify left)
			)
		)
		(property "Value" ""
			(at 0 0 180)
			(layer "F.Fab")
			(effects
				(font
					(size 1.27 1.27)
				)
			)
		)
		(duplicate_pad_numbers_are_jumpers no)
		(pad "A1" smd circle
			(at -5.999988 -5.999988 180)
			(size 0.4064 0.4064)
			(layers "F.Cu" "F.Mask" "F.Paste")
			(net "PVCCA_AUX_PLD")
		)
		(pad "A2" smd circle
			(at -5.199888 -5.999988 180)
			(size 0.4064 0.4064)
			(layers "F.Cu" "F.Mask" "F.Paste")
			(net "Net_316")
		)
		(pad "A3" smd circle
			(at -4.400042 -5.999988 180)
			(size 0.4064 0.4064)
			(layers "F.Cu" "F.Mask" "F.Paste")
			(net "BSM_PRSNT_R1_N")
		)
		(pad "A4" smd circle
			(at -3.599942 -5.999988 180)
			(size 0.4064 0.4064)
			(layers "F.Cu" "F.Mask" "F.Paste")
			(net "RST_PLTRST_R1_N")
		)
		(pad "A5" smd circle
			(at -2.800096 -5.999988 180)
			(size 0.4064 0.4064)
			(layers "F.Cu" "F.Mask" "F.Paste")
			(net "RST_RSMRST_N")
		)
		(pad "A6" smd circle
			(at -1.999996 -5.999988 180)
			(size 0.4064 0.4064)
			(layers "F.Cu" "F.Mask" "F.Paste")
			(net "JTAG_SCM_PLD_TDI")
		)
		(pad "A7" smd circle
			(at -1.199896 -5.999988 180)
			(size 0.4064 0.4064)
			(layers "F.Cu" "F.Mask" "F.Paste")
			(net "JTAG_SCM_PLD_TCK")
		)
		(pad "A8" smd circle
			(at -0.40005 -5.999988 180)
			(size 0.4064 0.4064)
			(layers "F.Cu" "F.Mask" "F.Paste")
			(net "IRQ_BMC_PCH_NMI_R_N")
		)
		(pad "A9" smd circle
			(at 0.40005 -5.999988 180)
			(size 0.4064 0.4064)
			(layers "F.Cu" "F.Mask" "F.Paste")
			(net "SMB_BMC_MM16_R3_SCL")
		)
		(pad "A10" smd circle
			(at 1.199896 -5.999988 180)
			(size 0.4064 0.4064)
			(layers "F.Cu" "F.Mask" "F.Paste")
			(net "Net_75")
		)
		(pad "A11" smd circle
			(at 1.999996 -5.999988 180)
			(size 0.4064 0.4064)
			(layers "F.Cu" "F.Mask" "F.Paste")
			(net "RST_EXTRST_R_N")
		)
		(pad "A12" smd circle
			(at 2.800096 -5.999988 180)
			(size 0.4064 0.4064)
			(layers "F.Cu" "F.Mask" "F.Paste")
			(net "FM_ADR_COMPLETE")
		)
		(pad "A13" smd circle
			(at 3.599942 -5.999988 180)
			(size 0.4064 0.4064)
			(layers "F.Cu" "F.Mask" "F.Paste")
			(net "PU_FPGA_NSTATUS")
		)
		(pad "A14" smd circle
			(at 4.400042 -5.999988 180)
			(size 0.4064 0.4064)
			(layers "F.Cu" "F.Mask" "F.Paste")
			(net "SGPIO_CLK_PLD_0")
		)
		(pad "A15" smd circle
			(at 5.199888 -5.999988 180)
			(size 0.4064 0.4064)
			(layers "F.Cu" "F.Mask" "F.Paste")
			(net "FM_THERMTRIP_DLY_LVC1_R_N")
		)
		(pad "A16" smd circle
			(at 5.999988 -5.999988 180)
			(size 0.4064 0.4064)
			(layers "F.Cu" "F.Mask" "F.Paste")
			(net "PVCCA_AUX_PLD")
		)
		(pad "B1" smd circle
			(at -5.999988 -5.199888 180)
			(size 0.4064 0.4064)
			(layers "F.Cu" "F.Mask" "F.Paste")
			(net "Net_298")
		)
		(pad "B2" smd circle
			(at -5.199888 -5.199888 180)
			(size 0.4064 0.4064)
			(layers "F.Cu" "F.Mask" "F.Paste")
			(net "GND")
		)
		(pad "B3" smd circle
			(at -4.400042 -5.199888 180)
			(size 0.4064 0.4064)
			(layers "F.Cu" "F.Mask" "F.Paste")
			(net "IRQ_BMC_CPU_NMI_R")
		)
		(pad "B4" smd circle
			(at -3.599942 -5.199888 180)
			(size 0.4064 0.4064)
			(layers "F.Cu" "F.Mask" "F.Paste")
			(net "RST_PCA9548_SENSOR_N")
		)
		(pad "B5" smd circle
			(at -2.800096 -5.199888 180)
			(size 0.4064 0.4064)
			(layers "F.Cu" "F.Mask" "F.Paste")
			(net "FM_TPM_PRSNT_1_R_N")
		)
		(pad "B6" smd circle
			(at -1.999996 -5.199888 180)
			(size 0.4064 0.4064)
			(layers "F.Cu" "F.Mask" "F.Paste")
			(net "FM_JTAG_BMC_MUX_SEL_R2")
		)
		(pad "B7" smd circle
			(at -1.199896 -5.199888 180)
			(size 0.4064 0.4064)
			(layers "F.Cu" "F.Mask" "F.Paste")
			(net "IRQ_UV_DETECT_N")
		)
		(pad "B8" smd circle
			(at -0.40005 -5.199888 180)
			(size 0.4064 0.4064)
			(layers "F.Cu" "F.Mask" "F.Paste")
			(net "JTAG_SCM_PLD_TMS")
		)
		(pad "B9" smd circle
			(at 0.40005 -5.199888 180)
			(size 0.4064 0.4064)
			(layers "F.Cu" "F.Mask" "F.Paste")
			(net "IRQ_PCH_SCI_WHEA_N")
		)
		(pad "B10" smd circle
			(at 1.199896 -5.199888 180)
			(size 0.4064 0.4064)
			(layers "F.Cu" "F.Mask" "F.Paste")
			(net "PU_PT20D")
		)
		(pad "B11" smd circle
			(at 1.999996 -5.199888 180)
			(size 0.4064 0.4064)
			(layers "F.Cu" "F.Mask" "F.Paste")
			(net "IRQ_OC_DETECT_N")
		)
		(pad "B12" smd circle
			(at 2.800096 -5.199888 180)
			(size 0.4064 0.4064)
			(layers "F.Cu" "F.Mask" "F.Paste")
			(net "SGPIO_PLD_LD_0")
		)
		(pad "B13" smd circle
			(at 3.599942 -5.199888 180)
			(size 0.4064 0.4064)
			(layers "F.Cu" "F.Mask" "F.Paste")
			(net "IRQ_OC_DETECT_EN_N")
		)
		(pad "B14" smd circle
			(at 4.400042 -5.199888 180)
			(size 0.4064 0.4064)
			(layers "F.Cu" "F.Mask" "F.Paste")
			(net "SGPIO_PLD_DI_0")
		)
		(pad "B15" smd circle
			(at 5.199888 -5.199888 180)
			(size 0.4064 0.4064)
			(layers "F.Cu" "F.Mask" "F.Paste")
			(net "GND")
		)
		(pad "B16" smd circle
			(at 5.999988 -5.199888 180)
			(size 0.4064 0.4064)
			(layers "F.Cu" "F.Mask" "F.Paste")
			(net "FM_PECI_SEL_N")
		)
		(pad "C1" smd circle
			(at -5.999988 -4.400042 180)
			(size 0.4064 0.4064)
			(layers "F.Cu" "F.Mask" "F.Paste")
			(net "Net_302")
		)
		(pad "C2" smd circle
			(at -5.199888 -4.400042 180)
			(size 0.4064 0.4064)
			(layers "F.Cu" "F.Mask" "F.Paste")
			(net "Net_299")
		)
		(pad "C3" smd circle
			(at -4.400042 -4.400042 180)
			(size 0.4064 0.4064)
			(layers "F.Cu" "F.Mask" "F.Paste")
			(net "GND")
		)
		(pad "C4" smd circle
			(at -3.599942 -4.400042 180)
			(size 0.4064 0.4064)
			(layers "F.Cu" "F.Mask" "F.Paste")
			(net "FM_TPM_PRSNT_0_R_N")
		)
		(pad "C5" smd circle
			(at -2.800096 -4.400042 180)
			(size 0.4064 0.4064)
			(layers "F.Cu" "F.Mask" "F.Paste")
			(net "PWRGD_PSU_AC_PWROK_PLD")
		)
		(pad "C6" smd circle
			(at -1.999996 -4.400042 180)
			(size 0.4064 0.4064)
			(layers "F.Cu" "F.Mask" "F.Paste")
			(net "JTAG_SCM_PLD_TDO")
		)
		(pad "C7" smd circle
			(at -1.199896 -4.400042 180)
			(size 0.4064 0.4064)
			(layers "F.Cu" "F.Mask" "F.Paste")
			(net "RST_BMC_RSTBTN_OUT_N")
		)
		(pad "C8" smd circle
			(at -0.40005 -4.400042 180)
			(size 0.4064 0.4064)
			(layers "F.Cu" "F.Mask" "F.Paste")
			(net "CLK_25M_OSC_FPGA")
		)
		(pad "C9" smd circle
			(at 0.40005 -4.400042 180)
			(size 0.4064 0.4064)
			(layers "F.Cu" "F.Mask" "F.Paste")
			(net "SMB_BMC_MM16_R3_SDA")
		)
		(pad "C10" smd circle
			(at 1.199896 -4.400042 180)
			(size 0.4064 0.4064)
			(layers "F.Cu" "F.Mask" "F.Paste")
			(net "JTAG_SCM_PLD_R_JTAGEN")
		)
		(pad "C11" smd circle
			(at 1.999996 -4.400042 180)
			(size 0.4064 0.4064)
			(layers "F.Cu" "F.Mask" "F.Paste")
			(net "PWRGD_CPUPWRGD_LVC1")
		)
		(pad "C12" smd circle
			(at 2.800096 -4.400042 180)
			(size 0.4064 0.4064)
			(layers "F.Cu" "F.Mask" "F.Paste")
			(net "SGPIO_PLD_DO_0")
		)
		(pad "C13" smd circle
			(at 3.599942 -4.400042 180)
			(size 0.4064 0.4064)
			(layers "F.Cu" "F.Mask" "F.Paste")
			(net "PU_FPGA_CONFIG_DONE")
		)
	)
)
